(kicad_pcb
	(version 20241229)
	(generator "pcbnew")
	(generator_version "9.0")
	(general
		(thickness 1.62)
		(legacy_teardrops no)
	)
	(paper "A4")
	(title_block
		(title "OCuLink to 10GbE adapter")
		(date "2026-02-23")
		(rev "1.1.0")
		(company "Antmicro Ltd")
		(comment 1 "www.antmicro.com")
		(comment 9 "footprints 158-161 of 510")
	)
	(layers
		(0 "F.Cu" signal)
		(4 "In1.Cu" signal)
		(6 "In2.Cu" signal)
		(8 "In3.Cu" signal)
		(10 "In4.Cu" signal)
		(12 "In5.Cu" signal)
		(14 "In6.Cu" signal)
		(2 "B.Cu" signal)
		(9 "F.Adhes" user "F.Adhesive")
		(11 "B.Adhes" user "B.Adhesive")
		(13 "F.Paste" user)
		(15 "B.Paste" user)
		(5 "F.SilkS" user "F.Silkscreen")
		(7 "B.SilkS" user "B.Silkscreen")
		(1 "F.Mask" user)
		(3 "B.Mask" user)
		(17 "Dwgs.User" user "User.Drawings")
		(19 "Cmts.User" user "User.Comments")
		(21 "Eco1.User" user "User.Eco1")
		(23 "Eco2.User" user "User.Eco2")
		(25 "Edge.Cuts" user)
		(27 "Margin" user)
		(31 "F.CrtYd" user "F.Courtyard")
		(29 "B.CrtYd" user "B.Courtyard")
		(35 "F.Fab" user)
		(33 "B.Fab" user)
	)
	(footprint "antmicro-footprints:LED_0603_1608Metric_G"
		(layer "F.Cu")
		(at 90.75 52.65 -90)
		(descr "LED SMD 0603 Green")
		(tags "LED SMD 0603 Green")
		(property "Reference" "D15"
			(at -1.08 0.69 90)
			(layer "F.SilkS")
			(effects
				(font
					(size 0.7 0.7)
					(thickness 0.15)
				)
				(justify right bottom)
			)
		)
		(property "Value" "LED_G_0603_LG_L29K-G2J1-24-Z"
			(at -0.001 1.599 90)
			(layer "F.Fab")
			(hide yes)
			(effects
				(font
					(size 0.7 0.7)
					(thickness 0.15)
				)
				(justify right top)
			)
		)
		(property "Datasheet" "https://look.ams-osram.com/m/19ee86b3ae0ee95b/original/LG-L29K.pdf"
			(at 0 0 90)
			(layer "F.Fab")
			(hide yes)
			(effects
				(font
					(size 1.27 1.27)
					(thickness 0.15)
				)
			)
		)
		(property "Description" "LED, Green, SMD, 0603, 20 mA, 1.7 V, 570 nm"
			(at 0 0 90)
			(layer "F.Fab")
			(hide yes)
			(effects
				(font
					(size 1.27 1.27)
					(thickness 0.15)
				)
			)
		)
		(property "MPN" "LG L29K-G2J1-24-Z"
			(at 0 0 270)
			(unlocked yes)
			(layer "F.Fab")
			(hide yes)
			(effects
				(font
					(size 1 1)
					(thickness 0.15)
				)
			)
		)
		(property "Manufacturer" "OSRAM"
			(at 0 0 270)
			(unlocked yes)
			(layer "F.Fab")
			(hide yes)
			(effects
				(font
					(size 1 1)
					(thickness 0.15)
				)
			)
		)
		(property "Color" "Green"
			(at 0 0 270)
			(unlocked yes)
			(layer "F.Fab")
			(hide yes)
			(effects
				(font
					(size 1 1)
					(thickness 0.15)
				)
			)
		)
		(property "Author" "Antmicro"
			(at 0 0 270)
			(unlocked yes)
			(layer "F.Fab")
			(hide yes)
			(effects
				(font
					(size 1 1)
					(thickness 0.15)
				)
			)
		)
		(property "License" "Apache-2.0"
			(at 0 0 270)
			(unlocked yes)
			(layer "F.Fab")
			(hide yes)
			(effects
				(font
					(size 1 1)
					(thickness 0.15)
				)
			)
		)
		(sheetname "/OCuLink/")
		(sheetfile "oculink.kicad_sch")
		(attr smd)
		(fp_line
			(start 0.22 0.35)
			(end -0.22 0.35)
			(stroke
				(width 0.15)
				(type solid)
			)
			(layer "F.SilkS")
		)
		(fp_line
			(start -0.094672 0.201008)
			(end -0.094672 -0.198992)
			(stroke
				(width 0.1)
				(type solid)
			)
			(layer "F.SilkS")
		)
		(fp_line
			(start 0.105328 0.201008)
			(end -0.094672 0.001008)
			(stroke
				(width 0.1)
				(type solid)
			)
			(layer "F.SilkS")
		)
		(fp_line
			(start 0.105328 0.201008)
			(end 0.105328 -0.198992)
			(stroke
				(width 0.1)
				(type solid)
			)
			(layer "F.SilkS")
		)
		(fp_line
			(start -0.094672 0.001008)
			(end -0.24 0.001008)
			(stroke
				(width 0.1)
				(type solid)
			)
			(layer "F.SilkS")
		)
		(fp_line
			(start -0.094672 0.001008)
			(end 0.105328 -0.198992)
			(stroke
				(width 0.1)
				(type solid)
			)
			(layer "F.SilkS")
		)
		(fp_line
			(start 0.105328 0.001008)
			(end 0.24 0.001)
			(stroke
				(width 0.1)
				(type solid)
			)
			(layer "F.SilkS")
		)
		(fp_line
			(start -1.18 -0.319)
			(end -1.18 0.321)
			(stroke
				(width 0.15)
				(type solid)
			)
			(layer "F.SilkS")
		)
		(fp_line
			(start 0.22 -0.35)
			(end -0.22 -0.35)
			(stroke
				(width 0.15)
				(type solid)
			)
			(layer "F.SilkS")
		)
		(fp_rect
			(start 1.25 0.65)
			(end -1.25 -0.65)
			(stroke
				(width 0.05)
				(type solid)
			)
			(fill no)
			(layer "F.CrtYd")
		)
		(fp_line
			(start -0.199 0.2)
			(end -0.199 0.1)
			(stroke
				(width 0.15)
				(type solid)
			)
			(layer "F.Fab")
		)
		(fp_line
			(start 0.201 0.2)
			(end 0.201 0)
			(stroke
				(width 0.15)
				(type solid)
			)
			(layer "F.Fab")
		)
		(fp_line
			(start -0.199 0)
			(end -0.597 0)
			(stroke
				(width 0.15)
				(type solid)
			)
			(layer "F.Fab")
		)
		(fp_line
			(start -0.101 0)
			(end 0.201 0.2)
			(stroke
				(width 0.15)
				(type solid)
			)
			(layer "F.Fab")
		)
		(fp_line
			(start 0.201 0)
			(end 0.201 -0.202)
			(stroke
				(width 0.15)
				(type solid)
			)
			(layer "F.Fab")
		)
		(fp_line
			(start 0.599 0)
			(end 0.201 0)
			(stroke
				(width 0.15)
				(type solid)
			)
			(layer "F.Fab")
		)
		(fp_line
			(start -0.199 -0.202)
			(end -0.199 0.1)
			(stroke
				(width 0.15)
				(type solid)
			)
			(layer "F.Fab")
		)
		(fp_line
			(start 0.201 -0.202)
			(end -0.101 0)
			(stroke
				(width 0.15)
				(type solid)
			)
			(layer "F.Fab")
		)
		(fp_rect
			(start 0.848 0.4)
			(end -0.85 -0.402)
			(stroke
				(width 0.15)
				(type solid)
			)
			(fill no)
			(layer "F.Fab")
		)
		(fp_text user "License: Apache-2.0"
			(at -1.4224 3.599 270)
			(layer "F.Fab")
			(effects
				(font
					(size 0.7 0.7)
					(thickness 0.15)
				)
				(justify left bottom)
			)
		)
		(fp_text user "${REFERENCE}"
			(at -1.4224 5.999 270)
			(layer "F.Fab")
			(effects
				(font
					(size 0.7 0.7)
					(thickness 0.15)
				)
				(justify left bottom)
			)
		)
		(fp_text user "Author: Antmicro"
			(at -1.4224 4.799 270)
			(layer "F.Fab")
			(effects
				(font
					(size 0.7 0.7)
					(thickness 0.15)
				)
				(justify left bottom)
			)
		)
		(pad "1" smd roundrect
			(at -0.7 0 90)
			(size 0.8 1)
			(layers "F.Cu" "F.Mask" "F.Paste")
			(roundrect_rratio 0.2)
			(net 28 "GND")
			(pinfunction "C")
			(pintype "passive")
		)
		(pad "2" smd roundrect
			(at 0.7 0 90)
			(size 0.8 1)
			(layers "F.Cu" "F.Mask" "F.Paste")
			(roundrect_rratio 0.2)
			(net 410 "Net-(D15-A)")
			(pinfunction "A")
			(pintype "passive")
		)
	)
	(footprint "antmicro-footprints:C_0402_1005Metric"
		(layer "F.Cu")
		(at 54.4 88.5 -90)
		(descr "Capacitor SMD 0402")
		(tags "capacitor SMD 0402")
		(property "Reference" "C14"
			(at 1.25 1.55 90)
			(layer "F.SilkS")
			(effects
				(font
					(size 0.7 0.7)
					(thickness 0.15)
				)
				(justify right top)
			)
		)
		(property "Value" "C_100n_0402"
			(at -1.022927 2.155213 90)
			(layer "F.Fab")
			(hide yes)
			(effects
				(font
					(size 0.7 0.7)
					(thickness 0.15)
				)
				(justify right top)
			)
		)
		(property "Datasheet" "https://www.murata.com/products/productdetail?partno=GRM155R61H104KE14%23"
			(at 0 0 90)
			(layer "F.Fab")
			(hide yes)
			(effects
				(font
					(size 1.27 1.27)
					(thickness 0.15)
				)
			)
		)
		(property "Description" "SMD Multilayer Ceramic Capacitor, 0.1 µF, 50 V, 0402 [1005 Metric], ± 10%, X5R, GRM Series"
			(at 0 0 90)
			(layer "F.Fab")
			(hide yes)
			(effects
				(font
					(size 1.27 1.27)
					(thickness 0.15)
				)
			)
		)
		(property "MPN" "GRM155R61H104KE14D"
			(at 0 0 270)
			(unlocked yes)
			(layer "F.Fab")
			(hide yes)
			(effects
				(font
					(size 1 1)
					(thickness 0.15)
				)
			)
		)
		(property "Manufacturer" "Murata"
			(at 0 0 270)
			(unlocked yes)
			(layer "F.Fab")
			(hide yes)
			(effects
				(font
					(size 1 1)
					(thickness 0.15)
				)
			)
		)
		(property "License" "Apache-2.0"
			(at 0 0 270)
			(unlocked yes)
			(layer "F.Fab")
			(hide yes)
			(effects
				(font
					(size 1 1)
					(thickness 0.15)
				)
			)
		)
		(property "Author" "Antmicro"
			(at 0 0 270)
			(unlocked yes)
			(layer "F.Fab")
			(hide yes)
			(effects
				(font
					(size 1 1)
					(thickness 0.15)
				)
			)
		)
		(property "Val" "100n"
			(at 0 0 270)
			(unlocked yes)
			(layer "F.Fab")
			(hide yes)
			(effects
				(font
					(size 1 1)
					(thickness 0.15)
				)
			)
		)
		(property "Voltage" "50V"
			(at 0 0 270)
			(unlocked yes)
			(layer "F.Fab")
			(hide yes)
			(effects
				(font
					(size 1 1)
					(thickness 0.15)
				)
			)
		)
		(property "Dielectric" "X5R"
			(at 0 0 270)
			(unlocked yes)
			(layer "F.Fab")
			(hide yes)
			(effects
				(font
					(size 1 1)
					(thickness 0.15)
				)
			)
		)
		(sheetname "/Power/")
		(sheetfile "power.kicad_sch")
		(attr smd)
		(fp_rect
			(start -0.925 -0.47)
			(end 0.925 0.47)
			(stroke
				(width 0.05)
				(type default)
			)
			(fill no)
			(layer "F.CrtYd")
		)
		(fp_line
			(start -0.494 0.248)
			(end -0.494 -0.25)
			(stroke
				(width 0.15)
				(type solid)
			)
			(layer "F.Fab")
		)
		(fp_line
			(start 0.504 0.248)
			(end -0.494 0.248)
			(stroke
				(width 0.15)
				(type solid)
			)
			(layer "F.Fab")
		)
		(fp_line
			(start -0.494 -0.25)
			(end 0.504 -0.25)
			(stroke
				(width 0.15)
				(type solid)
			)
			(layer "F.Fab")
		)
		(fp_line
			(start 0.504 -0.25)
			(end 0.504 0.248)
			(stroke
				(width 0.15)
				(type solid)
			)
			(layer "F.Fab")
		)
		(pad "1" smd roundrect
			(at -0.48 0 270)
			(size 0.59 0.64)
			(layers "F.Cu" "F.Mask" "F.Paste")
			(roundrect_rratio 0.25)
			(net 28 "GND")
			(pintype "passive")
		)
		(pad "2" smd roundrect
			(at 0.48 0 270)
			(size 0.59 0.64)
			(layers "F.Cu" "F.Mask" "F.Paste")
			(roundrect_rratio 0.25)
			(net 314 "VCC")
			(pintype "passive")
		)
	)
	(footprint "antmicro-footprints:USON-10_2.5x1mm_P0.5mm"
		(layer "F.Cu")
		(at 100.25 59.985 -90)
		(descr "USON-10 2.5x1mm_ Pitch 0.5mm")
		(tags "USON-10 2.5x1mm Pitch 0.5mm")
		(property "Reference" "D6"
			(at 1.7 0.7 180)
			(layer "F.SilkS")
			(effects
				(font
					(size 0.7 0.7)
					(thickness 0.15)
				)
				(justify left bottom)
			)
		)
		(property "Value" "ESD204DQAR"
			(at 0.018 2.499 90)
			(layer "F.Fab")
			(hide yes)
			(effects
				(font
					(size 0.7 0.7)
					(thickness 0.15)
				)
				(justify right top)
			)
		)
		(property "Datasheet" "https://www.ti.com/lit/ds/symlink/esd204.pdf?ts=1706004844383&ref_url=https%253A%252F%252Fwww.ti.com%252Finterface%252Fdiodes%252Fesd-protection-diodes%252Fproducts.html"
			(at 0 0 90)
			(layer "F.Fab")
			(hide yes)
			(effects
				(font
					(size 1.27 1.27)
					(thickness 0.15)
				)
			)
		)
		(property "Description" "TVS diode array, 30 kV, USON-10, 3.6 V, 0.55 pF"
			(at 0 0 90)
			(layer "F.Fab")
			(hide yes)
			(effects
				(font
					(size 1.27 1.27)
					(thickness 0.15)
				)
			)
		)
		(property "MPN" "ESD204DQAR"
			(at 0 0 270)
			(unlocked yes)
			(layer "F.Fab")
			(hide yes)
			(effects
				(font
					(size 1 1)
					(thickness 0.15)
				)
			)
		)
		(property "Manufacturer" "Texas Instruments"
			(at 0 0 270)
			(unlocked yes)
			(layer "F.Fab")
			(hide yes)
			(effects
				(font
					(size 1 1)
					(thickness 0.15)
				)
			)
		)
		(property "Author" "Antmicro"
			(at 0 0 270)
			(unlocked yes)
			(layer "F.Fab")
			(hide yes)
			(effects
				(font
					(size 1 1)
					(thickness 0.15)
				)
			)
		)
		(property "License" "Apache-2.0"
			(at 0 0 270)
			(unlocked yes)
			(layer "F.Fab")
			(hide yes)
			(effects
				(font
					(size 1 1)
					(thickness 0.15)
				)
			)
		)
		(sheetname "/OCuLink/")
		(sheetfile "oculink.kicad_sch")
		(attr smd)
		(fp_line
			(start 0.498 1.398)
			(end -0.5 1.398)
			(stroke
				(width 0.15)
				(type solid)
			)
			(layer "F.SilkS")
		)
		(fp_line
			(start 0.498 -1.401)
			(end -0.5 -1.401)
			(stroke
				(width 0.15)
				(type solid)
			)
			(layer "F.SilkS")
		)
		(fp_circle
			(center -0.68 -1.27)
			(end -0.63 -1.27)
			(stroke
				(width 0.15)
				(type solid)
			)
			(fill yes)
			(layer "F.SilkS")
		)
		(fp_rect
			(start -0.8 -1.5)
			(end 0.8 1.499)
			(stroke
				(width 0.05)
				(type solid)
			)
			(fill no)
			(layer "F.CrtYd")
		)
		(fp_line
			(start -0.5 1.249)
			(end 0.498 1.249)
			(stroke
				(width 0.15)
				(type solid)
			)
			(layer "F.Fab")
		)
		(fp_line
			(start -0.5 -1)
			(end -0.5 1.249)
			(stroke
				(width 0.15)
				(type solid)
			)
			(layer "F.Fab")
		)
		(fp_line
			(start -0.25 -1.25)
			(end -0.5 -1)
			(stroke
				(width 0.15)
				(type solid)
			)
			(layer "F.Fab")
		)
		(fp_line
			(start 0.498 -1.25)
			(end 0.498 1.249)
			(stroke
				(width 0.15)
				(type solid)
			)
			(layer "F.Fab")
		)
		(fp_line
			(start 0.498 -1.25)
			(end -0.25 -1.25)
			(stroke
				(width 0.15)
				(type solid)
			)
			(layer "F.Fab")
		)
		(pad "1" smd roundrect
			(at -0.387 -1 180)
			(size 0.25 0.55)
			(layers "F.Cu" "F.Mask" "F.Paste")
			(roundrect_rratio 0.25)
			(net 117 "unconnected-(D6-Pad1)")
			(pintype "passive+no_connect")
		)
		(pad "2" smd roundrect
			(at -0.387 -0.5 180)
			(size 0.25 0.55)
			(layers "F.Cu" "F.Mask" "F.Paste")
			(roundrect_rratio 0.25)
			(net 320 "/OCuLink/~{CWAKE}_R")
			(pintype "passive")
		)
		(pad "3" smd roundrect
			(at -0.387 0 180)
			(size 0.4 0.55)
			(layers "F.Cu" "F.Mask" "F.Paste")
			(roundrect_rratio 0.25)
			(net 28 "GND")
			(pintype "power_in")
		)
		(pad "4" smd roundrect
			(at -0.387 0.498 180)
			(size 0.25 0.55)
			(layers "F.Cu" "F.Mask" "F.Paste")
			(roundrect_rratio 0.25)
			(net 42 "/OCuLink/REFCLK.+")
			(pintype "passive")
		)
		(pad "5" smd roundrect
			(at -0.387 0.998 180)
			(size 0.25 0.55)
			(layers "F.Cu" "F.Mask" "F.Paste")
			(roundrect_rratio 0.25)
			(net 45 "/OCuLink/REFCLK.-")
			(pintype "passive")
		)
		(pad "6" smd roundrect
			(at 0.385 0.998 180)
			(size 0.25 0.55)
			(layers "F.Cu" "F.Mask" "F.Paste")
			(roundrect_rratio 0.25)
			(net 45 "/OCuLink/REFCLK.-")
			(pintype "passive")
		)
		(pad "7" smd roundrect
			(at 0.385 0.498 180)
			(size 0.25 0.55)
			(layers "F.Cu" "F.Mask" "F.Paste")
			(roundrect_rratio 0.25)
			(net 42 "/OCuLink/REFCLK.+")
			(pintype "passive")
		)
		(pad "8" smd roundrect
			(at 0.385 0 180)
			(size 0.4 0.55)
			(layers "F.Cu" "F.Mask" "F.Paste")
			(roundrect_rratio 0.25)
			(net 28 "GND")
			(pintype "passive")
		)
		(pad "9" smd roundrect
			(at 0.385 -0.5 180)
			(size 0.25 0.55)
			(layers "F.Cu" "F.Mask" "F.Paste")
			(roundrect_rratio 0.25)
			(net 320 "/OCuLink/~{CWAKE}_R")
			(pintype "passive")
		)
		(pad "10" smd roundrect
			(at 0.385 -1 180)
			(size 0.25 0.55)
			(layers "F.Cu" "F.Mask" "F.Paste")
			(roundrect_rratio 0.25)
			(net 118 "unconnected-(D6-Pad1)_1")
			(pintype "passive+no_connect")
		)
	)
	(footprint "antmicro-footprints:C_0402_1005Metric"
		(layer "F.Cu")
		(at 97 65.285 -90)
		(descr "Capacitor SMD 0402")
		(tags "capacitor SMD 0402")
		(property "Reference" "C196"
			(at 0.842273 -0.499995 270)
			(layer "F.SilkS")
			(effects
				(font
					(size 0.7 0.7)
					(thickness 0.15)
				)
				(justify right bottom)
			)
		)
		(property "Value" "C_220n_16V_0402"
			(at -1.022927 2.155213 270)
			(layer "F.Fab")
			(hide yes)
			(effects
				(font
					(size 0.7 0.7)
					(thickness 0.15)
				)
				(justify left bottom)
			)
		)
		(property "Datasheet" "https://www.murata.com/products/productdetail?partno=GRM155R71C224KA12%23"
			(at 0 0 270)
			(layer "F.Fab")
			(hide yes)
			(effects
				(font
					(size 1.27 1.27)
					(thickness 0.15)
				)
			)
		)
		(property "Description" "SMD Multilayer Ceramic Capacitor, 0.22 µF, 16 V, 0402 [1005 Metric], ± 10%, X7R, GRM Series"
			(at 0 0 270)
			(layer "F.Fab")
			(hide yes)
			(effects
				(font
					(size 1.27 1.27)
					(thickness 0.15)
				)
			)
		)
		(property "MPN" "GRM155R71C224KA12D"
			(at 0 0 270)
			(unlocked yes)
			(layer "F.Fab")
			(hide yes)
			(effects
				(font
					(size 1 1)
					(thickness 0.15)
				)
			)
		)
		(property "Manufacturer" "Murata"
			(at 0 0 270)
			(unlocked yes)
			(layer "F.Fab")
			(hide yes)
			(effects
				(font
					(size 1 1)
					(thickness 0.15)
				)
			)
		)
		(property "License" "Apache-2.0"
			(at 0 0 270)
			(unlocked yes)
			(layer "F.Fab")
			(hide yes)
			(effects
				(font
					(size 1 1)
					(thickness 0.15)
				)
			)
		)
		(property "Author" "Antmicro"
			(at 0 0 270)
			(unlocked yes)
			(layer "F.Fab")
			(hide yes)
			(effects
				(font
					(size 1 1)
					(thickness 0.15)
				)
			)
		)
		(property "Val" "220n"
			(at 0 0 270)
			(unlocked yes)
			(layer "F.Fab")
			(hide yes)
			(effects
				(font
					(size 1 1)
					(thickness 0.15)
				)
			)
		)
		(property "Voltage" "16V"
			(at 0 0 270)
			(unlocked yes)
			(layer "F.Fab")
			(hide yes)
			(effects
				(font
					(size 1 1)
					(thickness 0.15)
				)
			)
		)
		(property "Dielectric" "X7R"
			(at 0 0 270)
			(unlocked yes)
			(layer "F.Fab")
			(hide yes)
			(effects
				(font
					(size 1 1)
					(thickness 0.15)
				)
			)
		)
		(sheetname "/X710-AT2 PCIe/")
		(sheetfile "x710-at2-pcie.kicad_sch")
		(attr smd)
		(fp_rect
			(start -0.925 -0.47)
			(end 0.925 0.47)
			(stroke
				(width 0.05)
				(type default)
			)
			(fill no)
			(layer "F.CrtYd")
		)
		(fp_line
			(start -0.494 0.248)
			(end -0.494 -0.25)
			(stroke
				(width 0.15)
				(type solid)
			)
			(layer "F.Fab")
		)
		(fp_line
			(start 0.504 0.248)
			(end -0.494 0.248)
			(stroke
				(width 0.15)
				(type solid)
			)
			(layer "F.Fab")
		)
		(fp_line
			(start -0.494 -0.25)
			(end 0.504 -0.25)
			(stroke
				(width 0.15)
				(type solid)
			)
			(layer "F.Fab")
		)
		(fp_line
			(start 0.504 -0.25)
			(end 0.504 0.248)
			(stroke
				(width 0.15)
				(type solid)
			)
			(layer "F.Fab")
		)
		(pad "1" smd roundrect
			(at -0.48 0 270)
			(size 0.59 0.64)
			(layers "F.Cu" "F.Mask" "F.Paste")
			(roundrect_rratio 0.25)
			(net 25 "/OCuLink/PCIe_{x4}.TX3+")
			(pintype "passive")
		)
		(pad "2" smd roundrect
			(at 0.48 0 270)
			(size 0.59 0.64)
			(layers "F.Cu" "F.Mask" "F.Paste")
			(roundrect_rratio 0.25)
			(net 44 "/X710-AT2 PCIe/PCIe_{x4}_AC.TX3+")
			(pintype "passive")
		)
	)
)
